(kicad_pcb
	(version 20241229)
	(generator "pcbnew")
	(generator_version "9.0")
	(general
		(thickness 1.62)
		(legacy_teardrops no)
	)
	(paper "A4")
	(title_block
		(title "OCuLink to 10GbE adapter")
		(date "2026-02-23")
		(rev "1.1.0")
		(company "Antmicro Ltd")
		(comment 1 "www.antmicro.com")
		(comment 9 "footprint 265 of 510 (U9), pads 1-84 of 503")
	)
	(layers
		(0 "F.Cu" signal)
		(4 "In1.Cu" signal)
		(6 "In2.Cu" signal)
		(8 "In3.Cu" signal)
		(10 "In4.Cu" signal)
		(12 "In5.Cu" signal)
		(14 "In6.Cu" signal)
		(2 "B.Cu" signal)
		(9 "F.Adhes" user "F.Adhesive")
		(11 "B.Adhes" user "B.Adhesive")
		(13 "F.Paste" user)
		(15 "B.Paste" user)
		(5 "F.SilkS" user "F.Silkscreen")
		(7 "B.SilkS" user "B.Silkscreen")
		(1 "F.Mask" user)
		(3 "B.Mask" user)
		(17 "Dwgs.User" user "User.Drawings")
		(19 "Cmts.User" user "User.Comments")
		(21 "Eco1.User" user "User.Eco1")
		(23 "Eco2.User" user "User.Eco2")
		(25 "Edge.Cuts" user)
		(27 "Margin" user)
		(31 "F.CrtYd" user "F.Courtyard")
		(29 "B.CrtYd" user "B.Courtyard")
		(35 "F.Fab" user)
		(33 "B.Fab" user)
	)
	(footprint "antmicro-footprints:FCBGA-503_22x22mm_Layout21x24_P1mm"
		(locked yes)
		(layer "F.Cu")
		(at 84.975 100 180)
		(property "Reference" "U9"
			(at -11.275 11.4 0)
			(layer "F.SilkS")
			(effects
				(font
					(size 0.7 0.7)
					(thickness 0.15)
				)
				(justify right bottom)
			)
		)
		(property "Value" "EZX710AT2_S_LMR5"
			(at -11.4 12.5 0)
			(layer "F.Fab")
			(hide yes)
			(effects
				(font
					(size 0.7 0.7)
					(thickness 0.15)
				)
				(justify right top)
			)
		)
		(property "Datasheet" "https://www.google.com/url?sa=t&source=web&rct=j&opi=89978449&url=https://cdrdv2-public.intel.com/596333/596333_X710-TM4_Datasheet_v_2_4.pdf&ved=2ahUKEwiSuv20_sCOAxXVCRAIHdxGO_UQFnoECBEQAQ&usg=AOvVaw1CjGyrGWE8ZvOdw4VBsY6U"
			(at -16.625 -13.91 0)
			(layer "F.Fab")
			(hide yes)
			(effects
				(font
					(size 0.7 0.7)
					(thickness 0.15)
				)
				(justify right top)
			)
		)
		(property "Description" "Ethernet ICs Intel Ethernet Controller 10 Gigabit X7"
			(at -12.015 -0.89 0)
			(layer "F.Fab")
			(hide yes)
			(effects
				(font
					(size 0.7 0.7)
					(thickness 0.15)
				)
				(justify right top)
			)
		)
		(property "MPN" "EZX710AT2 S LMR5"
			(at 0 0 180)
			(unlocked yes)
			(layer "F.Fab")
			(hide yes)
			(effects
				(font
					(size 1 1)
					(thickness 0.15)
				)
			)
		)
		(property "Manufacturer" "Intel"
			(at 0 0 180)
			(unlocked yes)
			(layer "F.Fab")
			(hide yes)
			(effects
				(font
					(size 1 1)
					(thickness 0.15)
				)
			)
		)
		(property "Author" "Antmicro"
			(at 0 0 180)
			(unlocked yes)
			(layer "F.Fab")
			(hide yes)
			(effects
				(font
					(size 1 1)
					(thickness 0.15)
				)
			)
		)
		(property "License" "Apache-2.0"
			(at 0 0 180)
			(unlocked yes)
			(layer "F.Fab")
			(hide yes)
			(effects
				(font
					(size 1 1)
					(thickness 0.15)
				)
			)
		)
		(sheetname "/X710-AT2 power/")
		(sheetfile "x710-at2-power.kicad_sch")
		(attr smd)
		(pad "A3" smd circle
			(at -9.25 -9.95 180)
			(size 0.5 0.5)
			(layers "F.Cu" "F.Mask" "F.Paste")
			(net 28 "GND")
			(pinfunction "VSSA")
			(pintype "power_in")
		)
		(pad "A5" smd circle
			(at -8.25 -9.95 180)
			(size 0.5 0.5)
			(layers "F.Cu" "F.Mask" "F.Paste")
			(net 349 "unconnected-(U9B-SER1_RX_N-PadA5)")
			(pinfunction "SER1_RX_N")
			(pintype "input+no_connect")
		)
		(pad "A7" smd circle
			(at -7.25 -9.95 180)
			(size 0.5 0.5)
			(layers "F.Cu" "F.Mask" "F.Paste")
			(net 28 "GND")
			(pinfunction "VSSA")
			(pintype "passive")
		)
		(pad "A9" smd circle
			(at -6.25 -9.95 180)
			(size 0.5 0.5)
			(layers "F.Cu" "F.Mask" "F.Paste")
			(net 265 "unconnected-(U9B-SER1_TX_P-PadA9)")
			(pinfunction "SER1_TX_P")
			(pintype "output+no_connect")
		)
		(pad "A11" smd circle
			(at -5.25 -9.95 180)
			(size 0.5 0.5)
			(layers "F.Cu" "F.Mask" "F.Paste")
			(net 28 "GND")
			(pinfunction "VSSA")
			(pintype "passive")
		)
		(pad "A13" smd circle
			(at -4.25 -9.95 180)
			(size 0.5 0.5)
			(layers "F.Cu" "F.Mask" "F.Paste")
			(net 178 "unconnected-(U9B-SER0_RX_N-PadA13)")
			(pinfunction "SER0_RX_N")
			(pintype "input+no_connect")
		)
		(pad "A15" smd circle
			(at -3.25 -9.95 180)
			(size 0.5 0.5)
			(layers "F.Cu" "F.Mask" "F.Paste")
			(net 28 "GND")
			(pinfunction "VSSA")
			(pintype "passive")
		)
		(pad "A17" smd circle
			(at -2.25 -9.95 180)
			(size 0.5 0.5)
			(layers "F.Cu" "F.Mask" "F.Paste")
			(net 192 "unconnected-(U9B-SER0_TX_P-PadA17)")
			(pinfunction "SER0_TX_P")
			(pintype "output+no_connect")
		)
		(pad "A19" smd circle
			(at -1.25 -9.95 180)
			(size 0.5 0.5)
			(layers "F.Cu" "F.Mask" "F.Paste")
			(net 28 "GND")
			(pinfunction "VSSA")
			(pintype "passive")
		)
		(pad "A21" smd circle
			(at -0.25 -9.95 180)
			(size 0.5 0.5)
			(layers "F.Cu" "F.Mask" "F.Paste")
			(net 28 "GND")
			(pinfunction "AVSS")
			(pintype "power_in")
		)
		(pad "A23" smd circle
			(at 0.75 -9.95 180)
			(size 0.5 0.5)
			(layers "F.Cu" "F.Mask" "F.Paste")
			(net 69 "/2xRJ45/Ethernet_P1.D1+")
			(pinfunction "P1_A_P")
			(pintype "bidirectional")
		)
		(pad "A25" smd circle
			(at 1.75 -9.95 180)
			(size 0.5 0.5)
			(layers "F.Cu" "F.Mask" "F.Paste")
			(net 60 "/2xRJ45/Ethernet_P1.D2-")
			(pinfunction "P1_B_N")
			(pintype "bidirectional")
		)
		(pad "A27" smd circle
			(at 2.75 -9.95 180)
			(size 0.5 0.5)
			(layers "F.Cu" "F.Mask" "F.Paste")
			(net 63 "/2xRJ45/Ethernet_P1.D3+")
			(pinfunction "P1_C_P")
			(pintype "bidirectional")
		)
		(pad "A29" smd circle
			(at 3.75 -9.95 180)
			(size 0.5 0.5)
			(layers "F.Cu" "F.Mask" "F.Paste")
			(net 68 "/2xRJ45/Ethernet_P1.D4-")
			(pinfunction "P1_D_N")
			(pintype "bidirectional")
		)
		(pad "A31" smd circle
			(at 4.75 -9.95 180)
			(size 0.5 0.5)
			(layers "F.Cu" "F.Mask" "F.Paste")
			(net 28 "GND")
			(pinfunction "AVSS")
			(pintype "passive")
		)
		(pad "A33" smd circle
			(at 5.75 -9.95 180)
			(size 0.5 0.5)
			(layers "F.Cu" "F.Mask" "F.Paste")
			(net 55 "/2xRJ45/Ethernet_P0.D4+")
			(pinfunction "P0_D_P")
			(pintype "bidirectional")
		)
		(pad "A35" smd circle
			(at 6.75 -9.95 180)
			(size 0.5 0.5)
			(layers "F.Cu" "F.Mask" "F.Paste")
			(net 50 "/2xRJ45/Ethernet_P0.D3-")
			(pinfunction "P0_C_N")
			(pintype "bidirectional")
		)
		(pad "A37" smd circle
			(at 7.75 -9.95 180)
			(size 0.5 0.5)
			(layers "F.Cu" "F.Mask" "F.Paste")
			(net 51 "/2xRJ45/Ethernet_P0.D2+")
			(pinfunction "P0_B_P")
			(pintype "bidirectional")
		)
		(pad "A39" smd circle
			(at 8.75 -9.95 180)
			(size 0.5 0.5)
			(layers "F.Cu" "F.Mask" "F.Paste")
			(net 49 "/2xRJ45/Ethernet_P0.D1-")
			(pinfunction "P0_A_N")
			(pintype "bidirectional")
		)
		(pad "A41" smd circle
			(at 9.75 -9.95 180)
			(size 0.5 0.5)
			(layers "F.Cu" "F.Mask" "F.Paste")
			(net 175 "unconnected-(U9G-RSVDA41_NC-PadA41)")
			(pinfunction "RSVDA41_NC")
			(pintype "passive+no_connect")
		)
		(pad "AA1" smd circle
			(at -10.25 7.35 180)
			(size 0.5 0.5)
			(layers "F.Cu" "F.Mask" "F.Paste")
			(net 402 "/X710-AT2 PCIe/CLK+")
			(pinfunction "PE_CLK_P")
			(pintype "input")
		)
		(pad "AA3" smd circle
			(at -9.25 7.35 180)
			(size 0.5 0.5)
			(layers "F.Cu" "F.Mask" "F.Paste")
			(net 28 "GND")
			(pinfunction "VSSA")
			(pintype "passive")
		)
		(pad "AA5" smd circle
			(at -8.25 7.35 180)
			(size 0.5 0.5)
			(layers "F.Cu" "F.Mask" "F.Paste")
			(net 39 "/OCuLink/PCIe_{x4}.RX0+")
			(pinfunction "PER_0_P")
			(pintype "input")
		)
		(pad "AA7" smd circle
			(at -7.25 7.35 180)
			(size 0.5 0.5)
			(layers "F.Cu" "F.Mask" "F.Paste")
			(net 36 "/OCuLink/PCIe_{x4}.RX0-")
			(pinfunction "PER_0_N")
			(pintype "input")
		)
		(pad "AA9" smd circle
			(at -6.25 7.35 180)
			(size 0.5 0.5)
			(layers "F.Cu" "F.Mask" "F.Paste")
			(net 28 "GND")
			(pinfunction "VSSA")
			(pintype "passive")
		)
		(pad "AA11" smd circle
			(at -5.25 7.35 180)
			(size 0.5 0.5)
			(layers "F.Cu" "F.Mask" "F.Paste")
			(net 28 "GND")
			(pinfunction "VSSA")
			(pintype "passive")
		)
		(pad "AA13" smd circle
			(at -4.25 7.35 180)
			(size 0.5 0.5)
			(layers "F.Cu" "F.Mask" "F.Paste")
			(net 28 "GND")
			(pinfunction "VSSA")
			(pintype "passive")
		)
		(pad "AA15" smd circle
			(at -3.25 7.35 180)
			(size 0.5 0.5)
			(layers "F.Cu" "F.Mask" "F.Paste")
			(net 28 "GND")
			(pinfunction "VSSA")
			(pintype "passive")
		)
		(pad "AA17" smd circle
			(at -2.25 7.35 180)
			(size 0.5 0.5)
			(layers "F.Cu" "F.Mask" "F.Paste")
			(net 28 "GND")
			(pinfunction "VSSA")
			(pintype "passive")
		)
		(pad "AA19" smd circle
			(at -1.25 7.35 180)
			(size 0.5 0.5)
			(layers "F.Cu" "F.Mask" "F.Paste")
			(net 28 "GND")
			(pinfunction "VSSA")
			(pintype "passive")
		)
		(pad "AA21" smd circle
			(at -0.25 7.35 180)
			(size 0.5 0.5)
			(layers "F.Cu" "F.Mask" "F.Paste")
			(net 28 "GND")
			(pinfunction "VSSA")
			(pintype "passive")
		)
		(pad "AA23" smd circle
			(at 0.75 7.35 180)
			(size 0.5 0.5)
			(layers "F.Cu" "F.Mask" "F.Paste")
			(net 28 "GND")
			(pinfunction "VSSA")
			(pintype "passive")
		)
		(pad "AA25" smd circle
			(at 1.75 7.35 180)
			(size 0.5 0.5)
			(layers "F.Cu" "F.Mask" "F.Paste")
			(net 28 "GND")
			(pinfunction "VSSA")
			(pintype "passive")
		)
		(pad "AA27" smd circle
			(at 2.75 7.35 180)
			(size 0.5 0.5)
			(layers "F.Cu" "F.Mask" "F.Paste")
			(net 244 "unconnected-(U9A-PER_4_P-PadAA27)")
			(pinfunction "PER_4_P")
			(pintype "input+no_connect")
		)
		(pad "AA29" smd circle
			(at 3.75 7.35 180)
			(size 0.5 0.5)
			(layers "F.Cu" "F.Mask" "F.Paste")
			(net 28 "GND")
			(pinfunction "VSSA")
			(pintype "passive")
		)
		(pad "AA31" smd circle
			(at 4.75 7.35 180)
			(size 0.5 0.5)
			(layers "F.Cu" "F.Mask" "F.Paste")
			(net 267 "unconnected-(U9A-PER_5_N-PadAA31)")
			(pinfunction "PER_5_N")
			(pintype "input+no_connect")
		)
		(pad "AA33" smd circle
			(at 5.75 7.35 180)
			(size 0.5 0.5)
			(layers "F.Cu" "F.Mask" "F.Paste")
			(net 28 "GND")
			(pinfunction "VSSA")
			(pintype "passive")
		)
		(pad "AA35" smd circle
			(at 6.75 7.35 180)
			(size 0.5 0.5)
			(layers "F.Cu" "F.Mask" "F.Paste")
			(net 247 "unconnected-(U9A-PER_6_N-PadAA35)")
			(pinfunction "PER_6_N")
			(pintype "input+no_connect")
		)
		(pad "AA37" smd circle
			(at 7.75 7.35 180)
			(size 0.5 0.5)
			(layers "F.Cu" "F.Mask" "F.Paste")
			(net 28 "GND")
			(pinfunction "VSSA")
			(pintype "passive")
		)
		(pad "AA39" smd circle
			(at 8.75 7.35 180)
			(size 0.5 0.5)
			(layers "F.Cu" "F.Mask" "F.Paste")
			(net 202 "unconnected-(U9A-PER_7_N-PadAA39)")
			(pinfunction "PER_7_N")
			(pintype "input+no_connect")
		)
		(pad "AA41" smd circle
			(at 9.75 7.35 180)
			(size 0.5 0.5)
			(layers "F.Cu" "F.Mask" "F.Paste")
			(net 28 "GND")
			(pinfunction "VSSA")
			(pintype "passive")
		)
		(pad "AB2" smd circle
			(at -9.75 8.215 180)
			(size 0.5 0.5)
			(layers "F.Cu" "F.Mask" "F.Paste")
			(net 403 "/X710-AT2 PCIe/CLK-")
			(pinfunction "PE_CLK_N")
			(pintype "input")
		)
		(pad "AB4" smd circle
			(at -8.75 8.215 180)
			(size 0.5 0.5)
			(layers "F.Cu" "F.Mask" "F.Paste")
			(net 28 "GND")
			(pinfunction "VSSA")
			(pintype "passive")
		)
		(pad "AB6" smd circle
			(at -7.75 8.215 180)
			(size 0.5 0.5)
			(layers "F.Cu" "F.Mask" "F.Paste")
			(net 28 "GND")
			(pinfunction "VSSA")
			(pintype "passive")
		)
		(pad "AB8" smd circle
			(at -6.75 8.215 180)
			(size 0.5 0.5)
			(layers "F.Cu" "F.Mask" "F.Paste")
			(net 28 "GND")
			(pinfunction "VSSA")
			(pintype "passive")
		)
		(pad "AB10" smd circle
			(at -5.75 8.215 180)
			(size 0.5 0.5)
			(layers "F.Cu" "F.Mask" "F.Paste")
			(net 37 "/OCuLink/PCIe_{x4}.RX1+")
			(pinfunction "PER_1_P")
			(pintype "input")
		)
		(pad "AB12" smd circle
			(at -4.75 8.215 180)
			(size 0.5 0.5)
			(layers "F.Cu" "F.Mask" "F.Paste")
			(net 34 "/OCuLink/PCIe_{x4}.RX1-")
			(pinfunction "PER_1_N")
			(pintype "input")
		)
		(pad "AB14" smd circle
			(at -3.75 8.215 180)
			(size 0.5 0.5)
			(layers "F.Cu" "F.Mask" "F.Paste")
			(net 28 "GND")
			(pinfunction "VSSA")
			(pintype "passive")
		)
		(pad "AB16" smd circle
			(at -2.75 8.215 180)
			(size 0.5 0.5)
			(layers "F.Cu" "F.Mask" "F.Paste")
			(net 80 "/OCuLink/PCIe_{x4}.RX2+")
			(pinfunction "PER_2_P")
			(pintype "input")
		)
		(pad "AB18" smd circle
			(at -1.75 8.215 180)
			(size 0.5 0.5)
			(layers "F.Cu" "F.Mask" "F.Paste")
			(net 104 "/OCuLink/PCIe_{x4}.RX2-")
			(pinfunction "PER_2_N")
			(pintype "input")
		)
		(pad "AB20" smd circle
			(at -0.75 8.215 180)
			(size 0.5 0.5)
			(layers "F.Cu" "F.Mask" "F.Paste")
			(net 28 "GND")
			(pinfunction "VSSA")
			(pintype "passive")
		)
		(pad "AB22" smd circle
			(at 0.25 8.215 180)
			(size 0.5 0.5)
			(layers "F.Cu" "F.Mask" "F.Paste")
			(net 98 "/OCuLink/PCIe_{x4}.RX3+")
			(pinfunction "PER_3_P")
			(pintype "input")
		)
		(pad "AB24" smd circle
			(at 1.25 8.215 180)
			(size 0.5 0.5)
			(layers "F.Cu" "F.Mask" "F.Paste")
			(net 109 "/OCuLink/PCIe_{x4}.RX3-")
			(pinfunction "PER_3_N")
			(pintype "input")
		)
		(pad "AB26" smd circle
			(at 2.25 8.215 180)
			(size 0.5 0.5)
			(layers "F.Cu" "F.Mask" "F.Paste")
			(net 28 "GND")
			(pinfunction "VSSA")
			(pintype "passive")
		)
		(pad "AB28" smd circle
			(at 3.25 8.215 180)
			(size 0.5 0.5)
			(layers "F.Cu" "F.Mask" "F.Paste")
			(net 273 "unconnected-(U9A-PER_4_N-PadAB28)")
			(pinfunction "PER_4_N")
			(pintype "input+no_connect")
		)
		(pad "AB30" smd circle
			(at 4.25 8.215 180)
			(size 0.5 0.5)
			(layers "F.Cu" "F.Mask" "F.Paste")
			(net 28 "GND")
			(pinfunction "VSSA")
			(pintype "passive")
		)
		(pad "AB32" smd circle
			(at 5.25 8.215 180)
			(size 0.5 0.5)
			(layers "F.Cu" "F.Mask" "F.Paste")
			(net 28 "GND")
			(pinfunction "VSSA")
			(pintype "passive")
		)
		(pad "AB34" smd circle
			(at 6.25 8.215 180)
			(size 0.5 0.5)
			(layers "F.Cu" "F.Mask" "F.Paste")
			(net 28 "GND")
			(pinfunction "VSSA")
			(pintype "passive")
		)
		(pad "AB36" smd circle
			(at 7.25 8.215 180)
			(size 0.5 0.5)
			(layers "F.Cu" "F.Mask" "F.Paste")
			(net 28 "GND")
			(pinfunction "VSSA")
			(pintype "passive")
		)
		(pad "AB38" smd circle
			(at 8.25 8.215 180)
			(size 0.5 0.5)
			(layers "F.Cu" "F.Mask" "F.Paste")
			(net 28 "GND")
			(pinfunction "VSSA")
			(pintype "passive")
		)
		(pad "AB40" smd circle
			(at 9.25 8.215 180)
			(size 0.5 0.5)
			(layers "F.Cu" "F.Mask" "F.Paste")
			(net 28 "GND")
			(pinfunction "VSSA")
			(pintype "passive")
		)
		(pad "AB42" smd circle
			(at 10.25 8.215 180)
			(size 0.5 0.5)
			(layers "F.Cu" "F.Mask" "F.Paste")
			(net 99 "/X710-AT2 Misc/LAN_PWR_GOOD")
			(pinfunction "LAN_PWR_GOOD")
			(pintype "input")
		)
		(pad "AC1" smd circle
			(at -10.25 9.08 180)
			(size 0.5 0.5)
			(layers "F.Cu" "F.Mask" "F.Paste")
			(net 28 "GND")
			(pinfunction "VSSA")
			(pintype "passive")
		)
		(pad "AC3" smd circle
			(at -9.25 9.08 180)
			(size 0.5 0.5)
			(layers "F.Cu" "F.Mask" "F.Paste")
			(net 28 "GND")
			(pinfunction "VSSA")
			(pintype "passive")
		)
		(pad "AC5" smd circle
			(at -8.25 9.08 180)
			(size 0.5 0.5)
			(layers "F.Cu" "F.Mask" "F.Paste")
			(net 33 "/X710-AT2 PCIe/PCIe_{x4}_AC.TX0-")
			(pinfunction "PET_0_N")
			(pintype "output")
		)
		(pad "AC7" smd circle
			(at -7.25 9.08 180)
			(size 0.5 0.5)
			(layers "F.Cu" "F.Mask" "F.Paste")
			(net 28 "GND")
			(pinfunction "VSSA")
			(pintype "passive")
		)
		(pad "AC9" smd circle
			(at -6.25 9.08 180)
			(size 0.5 0.5)
			(layers "F.Cu" "F.Mask" "F.Paste")
			(net 28 "GND")
			(pinfunction "VSSA")
			(pintype "passive")
		)
		(pad "AC11" smd circle
			(at -5.25 9.08 180)
			(size 0.5 0.5)
			(layers "F.Cu" "F.Mask" "F.Paste")
			(net 28 "GND")
			(pinfunction "VSSA")
			(pintype "passive")
		)
		(pad "AC13" smd circle
			(at -4.25 9.08 180)
			(size 0.5 0.5)
			(layers "F.Cu" "F.Mask" "F.Paste")
			(net 28 "GND")
			(pinfunction "VSSA")
			(pintype "passive")
		)
		(pad "AC15" smd circle
			(at -3.25 9.08 180)
			(size 0.5 0.5)
			(layers "F.Cu" "F.Mask" "F.Paste")
			(net 28 "GND")
			(pinfunction "VSSA")
			(pintype "passive")
		)
		(pad "AC17" smd circle
			(at -2.25 9.08 180)
			(size 0.5 0.5)
			(layers "F.Cu" "F.Mask" "F.Paste")
			(net 28 "GND")
			(pinfunction "VSSA")
			(pintype "passive")
		)
		(pad "AC19" smd circle
			(at -1.25 9.08 180)
			(size 0.5 0.5)
			(layers "F.Cu" "F.Mask" "F.Paste")
			(net 28 "GND")
			(pinfunction "VSSA")
			(pintype "passive")
		)
		(pad "AC21" smd circle
			(at -0.25 9.08 180)
			(size 0.5 0.5)
			(layers "F.Cu" "F.Mask" "F.Paste")
			(net 28 "GND")
			(pinfunction "VSSA")
			(pintype "passive")
		)
		(pad "AC23" smd circle
			(at 0.75 9.08 180)
			(size 0.5 0.5)
			(layers "F.Cu" "F.Mask" "F.Paste")
			(net 28 "GND")
			(pinfunction "VSSA")
			(pintype "passive")
		)
		(pad "AC25" smd circle
			(at 1.75 9.08 180)
			(size 0.5 0.5)
			(layers "F.Cu" "F.Mask" "F.Paste")
			(net 28 "GND")
			(pinfunction "VSSA")
			(pintype "passive")
		)
		(pad "AC27" smd circle
			(at 2.75 9.08 180)
			(size 0.5 0.5)
			(layers "F.Cu" "F.Mask" "F.Paste")
			(net 28 "GND")
			(pinfunction "VSSA")
			(pintype "passive")
		)
		(pad "AC29" smd circle
			(at 3.75 9.08 180)
			(size 0.5 0.5)
			(layers "F.Cu" "F.Mask" "F.Paste")
			(net 28 "GND")
			(pinfunction "VSSA")
			(pintype "passive")
		)
		(pad "AC31" smd circle
			(at 4.75 9.08 180)
			(size 0.5 0.5)
			(layers "F.Cu" "F.Mask" "F.Paste")
			(net 252 "unconnected-(U9A-PET_5_P-PadAC31)")
			(pinfunction "PET_5_P")
			(pintype "output+no_connect")
		)
		(pad "AC33" smd circle
			(at 5.75 9.08 180)
			(size 0.5 0.5)
			(layers "F.Cu" "F.Mask" "F.Paste")
			(net 28 "GND")
			(pinfunction "VSSA")
			(pintype "passive")
		)
		(pad "AC35" smd circle
			(at 6.75 9.08 180)
			(size 0.5 0.5)
			(layers "F.Cu" "F.Mask" "F.Paste")
			(net 243 "unconnected-(U9A-PET_6_P-PadAC35)")
			(pinfunction "PET_6_P")
			(pintype "output+no_connect")
		)
		(pad "AC37" smd circle
			(at 7.75 9.08 180)
			(size 0.5 0.5)
			(layers "F.Cu" "F.Mask" "F.Paste")
			(net 28 "GND")
			(pinfunction "VSSA")
			(pintype "passive")
		)
		(pad "AC39" smd circle
			(at 8.75 9.08 180)
			(size 0.5 0.5)
			(layers "F.Cu" "F.Mask" "F.Paste")
			(net 307 "unconnected-(U9A-PET_7_P-PadAC39)")
			(pinfunction "PET_7_P")
			(pintype "output+no_connect")
		)
		(pad "AC41" smd circle
			(at 9.75 9.08 180)
			(size 0.5 0.5)
			(layers "F.Cu" "F.Mask" "F.Paste")
			(net 28 "GND")
			(pinfunction "VSSA")
			(pintype "passive")
		)
		(pad "AD2" smd circle
			(at -9.75 9.945 180)
			(size 0.5 0.5)
			(layers "F.Cu" "F.Mask" "F.Paste")
			(net 28 "GND")
			(pinfunction "VSSA")
			(pintype "passive")
		)
	)
)
